(kicad_pcb
	(version 20260206)
	(generator "pcbnew")
	(generator_version "10.0")
	(general
		(thickness 1.6)
		(legacy_teardrops no)
	)
	(paper "A4")
	(title_block
		(title "03242023_DA0F0TMBIJ0_F0T_Motherboard_J_brd_V01_OCP.brd")
		(comment 1 "Grand Teton / footprint 3039 of 6105 (U2), pads 1-105 of 4677")
	)
	(layers
		(0 "F.Cu" signal "TOP")
		(4 "In1.Cu" signal "GND")
		(6 "In2.Cu" signal "IN1")
		(8 "In3.Cu" signal "GND1")
		(10 "In4.Cu" signal "IN2")
		(12 "In5.Cu" signal "GND2")
		(14 "In6.Cu" signal "IN3")
		(16 "In7.Cu" signal "GND3")
		(18 "In8.Cu" signal "VCC")
		(20 "In9.Cu" signal "VCC1")
		(22 "In10.Cu" signal "GND4")
		(24 "In11.Cu" signal "IN4")
		(26 "In12.Cu" signal "GND5")
		(28 "In13.Cu" signal "IN5")
		(30 "In14.Cu" signal "GND6")
		(32 "In15.Cu" signal "IN6")
		(34 "In16.Cu" signal "GND7")
		(2 "B.Cu" signal "BOTTOM")
		(9 "F.Adhes" user "F.Adhesive")
		(11 "B.Adhes" user "B.Adhesive")
		(13 "F.Paste" user "Package Geometry/Pastemask Top")
		(15 "B.Paste" user "Package Geometry/Pastemask Bottom")
		(5 "F.SilkS" user "Ref Des/Silkscreen Top")
		(7 "B.SilkS" user "Ref Des/Silkscreen Bottom")
		(1 "F.Mask" user "Board Geometry/Soldermask Top")
		(3 "B.Mask" user "Board Geometry/Soldermask Bottom")
		(17 "Dwgs.User" user "User.Drawings")
		(19 "Cmts.User" user "User.Comments")
		(21 "Eco1.User" user "User.Eco1")
		(23 "Eco2.User" user "User.Eco2")
		(25 "Edge.Cuts" user "Board Geometry/Outline")
		(27 "Margin" user)
		(31 "F.CrtYd" user "Package Geometry/Place Bound Top")
		(29 "B.CrtYd" user "Package Geometry/Place Bound Bottom")
		(35 "F.Fab" user "Ref Des/Assembly Top")
		(33 "B.Fab" user "Ref Des/Assembly Bottom")
	)
	(footprint ""
		(layer "F.Cu")
		(at 359.870248 -251.76988 90)
		(property "Reference" "U2"
			(at -74.416158 -44.488608 0)
			(unlocked yes)
			(layer "F.SilkS")
			(effects
				(font
					(size 1.6002 1.1938)
					(thickness 0.1524)
				)
				(justify left)
			)
		)
		(property "Value" ""
			(at 0 0 90)
			(layer "F.Fab")
			(effects
				(font
					(size 1.27 1.27)
				)
			)
		)
		(duplicate_pad_numbers_are_jumpers no)
		(pad "A9" smd oval
			(at -30.914086 -27.074114 135)
			(size 0.381 0.4826)
			(drill
				(offset 0 -0.0508)
			)
			(layers "F.Cu" "F.Mask" "F.Paste")
			(net "M_A_CPU0_SB_DQS_DN<3>")
		)
		(pad "A11" smd oval
			(at -29.2862 -27.074114 90)
			(size 0.381 0.4826)
			(drill
				(offset 0 -0.0508)
			)
			(layers "F.Cu" "F.Mask" "F.Paste")
			(net "GND")
		)
		(pad "A13" smd oval
			(at -27.658314 -27.074114 90)
			(size 0.381 0.4826)
			(drill
				(offset 0 -0.0508)
			)
			(layers "F.Cu" "F.Mask" "F.Paste")
			(net "GND")
		)
		(pad "A15" smd oval
			(at -26.030682 -27.074114 90)
			(size 0.381 0.4826)
			(drill
				(offset 0 -0.0508)
			)
			(layers "F.Cu" "F.Mask" "F.Paste")
			(net "M_B_CPU0_SB_DQS_DN<3>")
		)
		(pad "A17" smd oval
			(at -24.402796 -27.074114 90)
			(size 0.381 0.4826)
			(drill
				(offset 0 -0.0508)
			)
			(layers "F.Cu" "F.Mask" "F.Paste")
			(net "GND")
		)
		(pad "A19" smd oval
			(at -22.77491 -27.074114 90)
			(size 0.381 0.4826)
			(drill
				(offset 0 -0.0508)
			)
			(layers "F.Cu" "F.Mask" "F.Paste")
			(net "GND")
		)
		(pad "A21" smd oval
			(at -21.147278 -27.074114 90)
			(size 0.381 0.4826)
			(drill
				(offset 0 -0.0508)
			)
			(layers "F.Cu" "F.Mask" "F.Paste")
			(net "M_A_CPU0_SB_DQS_DN<2>")
		)
		(pad "A23" smd oval
			(at -19.519392 -27.074114 90)
			(size 0.381 0.4826)
			(drill
				(offset 0 -0.0508)
			)
			(layers "F.Cu" "F.Mask" "F.Paste")
			(net "GND")
		)
		(pad "A25" smd oval
			(at -17.89176 -27.074114 90)
			(size 0.381 0.4826)
			(drill
				(offset 0 -0.0508)
			)
			(layers "F.Cu" "F.Mask" "F.Paste")
			(net "GND")
		)
		(pad "A27" smd oval
			(at -16.263874 -27.074114 90)
			(size 0.381 0.4826)
			(drill
				(offset 0 -0.0508)
			)
			(layers "F.Cu" "F.Mask" "F.Paste")
			(net "M_A_CPU0_SB_DQS_DN<1>")
		)
		(pad "A29" smd oval
			(at -14.635988 -27.074114 90)
			(size 0.381 0.4826)
			(drill
				(offset 0 -0.0508)
			)
			(layers "F.Cu" "F.Mask" "F.Paste")
			(net "GND")
		)
		(pad "A31" smd oval
			(at -13.008356 -27.074114 90)
			(size 0.381 0.4826)
			(drill
				(offset 0 -0.0508)
			)
			(layers "F.Cu" "F.Mask" "F.Paste")
			(net "GND")
		)
		(pad "A33" smd oval
			(at -11.380724 -27.074114 90)
			(size 0.381 0.4826)
			(drill
				(offset 0 -0.0508)
			)
			(layers "F.Cu" "F.Mask" "F.Paste")
			(net "M_A_CPU0_SB_DQS_DN<9>")
		)
		(pad "A35" smd oval
			(at -9.752838 -27.074114 90)
			(size 0.381 0.4826)
			(drill
				(offset 0 -0.0508)
			)
			(layers "F.Cu" "F.Mask" "F.Paste")
			(net "GND")
		)
		(pad "A37" smd oval
			(at -8.124952 -27.074114 90)
			(size 0.381 0.4826)
			(drill
				(offset 0 -0.0508)
			)
			(layers "F.Cu" "F.Mask" "F.Paste")
			(net "GND")
		)
		(pad "A39" smd oval
			(at -6.49732 -27.074114 90)
			(size 0.381 0.4826)
			(drill
				(offset 0 -0.0508)
			)
			(layers "F.Cu" "F.Mask" "F.Paste")
			(net "M_A_CPU0_SB_CA<6>")
		)
		(pad "A41" smd oval
			(at -4.869434 -27.074114 90)
			(size 0.381 0.4826)
			(drill
				(offset 0 -0.0508)
			)
			(layers "F.Cu" "F.Mask" "F.Paste")
			(net "GND")
		)
		(pad "A43" smd oval
			(at -3.241802 -27.074114 90)
			(size 0.381 0.4826)
			(drill
				(offset 0 -0.0508)
			)
			(layers "F.Cu" "F.Mask" "F.Paste")
			(net "PWRGD_DRAMPWRGD_CPU0_AB_LVC1_R")
		)
		(pad "A50" smd oval
			(at 4.055618 -26.964132 90)
			(size 0.381 0.4826)
			(drill
				(offset 0 -0.0508)
			)
			(layers "F.Cu" "F.Mask" "F.Paste")
			(net "GND")
		)
		(pad "A52" smd oval
			(at 5.68325 -26.964132 90)
			(size 0.381 0.4826)
			(drill
				(offset 0 -0.0508)
			)
			(layers "F.Cu" "F.Mask" "F.Paste")
			(net "M_A_CPU0_SA_CA<0>")
		)
		(pad "A54" smd oval
			(at 7.311136 -26.964132 90)
			(size 0.381 0.4826)
			(drill
				(offset 0 -0.0508)
			)
			(layers "F.Cu" "F.Mask" "F.Paste")
			(net "GND")
		)
		(pad "A56" smd oval
			(at 8.939022 -26.964132 90)
			(size 0.381 0.4826)
			(drill
				(offset 0 -0.0508)
			)
			(layers "F.Cu" "F.Mask" "F.Paste")
			(net "GND")
		)
		(pad "A58" smd oval
			(at 10.566654 -26.964132 90)
			(size 0.381 0.4826)
			(drill
				(offset 0 -0.0508)
			)
			(layers "F.Cu" "F.Mask" "F.Paste")
			(net "M_A_CPU0_SA_DQS_DN<4>")
		)
		(pad "A60" smd oval
			(at 12.19454 -26.964132 90)
			(size 0.381 0.4826)
			(drill
				(offset 0 -0.0508)
			)
			(layers "F.Cu" "F.Mask" "F.Paste")
			(net "GND")
		)
		(pad "A62" smd oval
			(at 13.822426 -26.964132 90)
			(size 0.381 0.4826)
			(drill
				(offset 0 -0.0508)
			)
			(layers "F.Cu" "F.Mask" "F.Paste")
			(net "GND")
		)
		(pad "A64" smd oval
			(at 15.450058 -26.964132 90)
			(size 0.381 0.4826)
			(drill
				(offset 0 -0.0508)
			)
			(layers "F.Cu" "F.Mask" "F.Paste")
			(net "M_A_CPU0_SA_DQS_DN<3>")
		)
		(pad "AA1" smd oval
			(at -37.425122 -17.676114 180)
			(size 0.381 0.4826)
			(drill
				(offset 0 -0.0508)
			)
			(layers "F.Cu" "F.Mask" "F.Paste")
			(net "UPI_CPU0_CPU1_P0P1_DN<6>")
		)
		(pad "AA3" smd circle
			(at -35.797236 -17.676114 270)
			(size 0.4318 0.4318)
			(layers "F.Cu" "F.Mask" "F.Paste")
			(net "PVCCFA_EHV_CPU0")
		)
		(pad "AA5" smd circle
			(at -34.169604 -17.676114 270)
			(size 0.4318 0.4318)
			(layers "F.Cu" "F.Mask" "F.Paste")
			(net "UPI_CPU1_CPU0_P1P0_DP<5>")
		)
		(pad "AA7" smd circle
			(at -32.541718 -17.676114 270)
			(size 0.4318 0.4318)
			(layers "F.Cu" "F.Mask" "F.Paste")
			(net "PVCCFA_EHV_FIVRA_CPU0")
		)
		(pad "AA9" smd circle
			(at -30.914086 -17.676114 270)
			(size 0.4318 0.4318)
			(layers "F.Cu" "F.Mask" "F.Paste")
			(net "P5E_CPU0_PE0_RX_DN<5>")
		)
		(pad "AA11" smd circle
			(at -29.2862 -17.676114 270)
			(size 0.4318 0.4318)
			(layers "F.Cu" "F.Mask" "F.Paste")
			(net "PVCCFA_EHV_FIVRA_CPU0")
		)
		(pad "AA13" smd circle
			(at -27.658314 -17.676114 270)
			(size 0.4318 0.4318)
			(layers "F.Cu" "F.Mask" "F.Paste")
			(net "P5E_CPU0_PE0_TX_DN<4>")
		)
		(pad "AA15" smd circle
			(at -26.030682 -17.676114 270)
			(size 0.4318 0.4318)
			(layers "F.Cu" "F.Mask" "F.Paste")
			(net "PVCCFA_EHV_FIVRA_CPU0")
		)
		(pad "AA17" smd circle
			(at -24.402796 -17.676114 270)
			(size 0.4318 0.4318)
			(layers "F.Cu" "F.Mask" "F.Paste")
			(net "M_C_CPU0_SB_DQ<28>")
		)
		(pad "AA19" smd circle
			(at -22.77491 -17.676114 270)
			(size 0.4318 0.4318)
			(layers "F.Cu" "F.Mask" "F.Paste")
			(net "GND")
		)
		(pad "AA21" smd circle
			(at -21.147278 -17.676114 270)
			(size 0.4318 0.4318)
			(layers "F.Cu" "F.Mask" "F.Paste")
			(net "M_C_CPU0_SB_DQS_DP<7>")
		)
		(pad "AA23" smd circle
			(at -19.519392 -17.676114 270)
			(size 0.4318 0.4318)
			(layers "F.Cu" "F.Mask" "F.Paste")
			(net "GND")
		)
		(pad "AA25" smd circle
			(at -17.89176 -17.676114 270)
			(size 0.4318 0.4318)
			(layers "F.Cu" "F.Mask" "F.Paste")
			(net "GND")
		)
		(pad "AA27" smd circle
			(at -16.263874 -17.676114 270)
			(size 0.4318 0.4318)
			(layers "F.Cu" "F.Mask" "F.Paste")
			(net "M_B_CPU0_SB_DQS_DP<5>")
		)
		(pad "AA29" smd circle
			(at -14.635988 -17.676114 270)
			(size 0.4318 0.4318)
			(layers "F.Cu" "F.Mask" "F.Paste")
			(net "GND")
		)
		(pad "AA31" smd circle
			(at -13.008356 -17.676114 270)
			(size 0.4318 0.4318)
			(layers "F.Cu" "F.Mask" "F.Paste")
			(net "GND")
		)
		(pad "AA33" smd circle
			(at -11.380724 -17.676114 270)
			(size 0.4318 0.4318)
			(layers "F.Cu" "F.Mask" "F.Paste")
			(net "M_C_CPU0_SB_DQS_DP<4>")
		)
		(pad "AA35" smd circle
			(at -9.752838 -17.676114 270)
			(size 0.4318 0.4318)
			(layers "F.Cu" "F.Mask" "F.Paste")
			(net "GND")
		)
		(pad "AA37" smd circle
			(at -8.124952 -17.676114 270)
			(size 0.4318 0.4318)
			(layers "F.Cu" "F.Mask" "F.Paste")
			(net "GND")
		)
		(pad "AA39" smd circle
			(at -6.49732 -17.676114 270)
			(size 0.4318 0.4318)
			(layers "F.Cu" "F.Mask" "F.Paste")
			(net "M_C_CPU0_SB_PAR")
		)
		(pad "AA41" smd circle
			(at -4.869434 -17.676114 270)
			(size 0.4318 0.4318)
			(layers "F.Cu" "F.Mask" "F.Paste")
			(net "GND")
		)
		(pad "AA43" smd circle
			(at -3.241802 -17.676114 270)
			(size 0.4318 0.4318)
			(layers "F.Cu" "F.Mask" "F.Paste")
			(net "GND")
		)
		(pad "AA45" smd circle
			(at -1.613916 -17.676114 270)
			(size 0.4318 0.4318)
			(layers "F.Cu" "F.Mask" "F.Paste")
			(net "M_B_CPU0_CLK_DP<1>")
		)
		(pad "AA48" smd circle
			(at 2.427732 -17.566132 270)
			(size 0.4318 0.4318)
			(layers "F.Cu" "F.Mask" "F.Paste")
			(net "GND")
		)
		(pad "AA50" smd circle
			(at 4.055618 -17.566132 270)
			(size 0.4318 0.4318)
			(layers "F.Cu" "F.Mask" "F.Paste")
			(net "GND")
		)
		(pad "AA52" smd circle
			(at 5.68325 -17.566132 270)
			(size 0.4318 0.4318)
			(layers "F.Cu" "F.Mask" "F.Paste")
			(net "M_C_CPU0_SA_CA<1>")
		)
		(pad "AA54" smd circle
			(at 7.311136 -17.566132 270)
			(size 0.4318 0.4318)
			(layers "F.Cu" "F.Mask" "F.Paste")
			(net "GND")
		)
		(pad "AA56" smd circle
			(at 8.939022 -17.566132 270)
			(size 0.4318 0.4318)
			(layers "F.Cu" "F.Mask" "F.Paste")
			(net "GND")
		)
		(pad "AA58" smd circle
			(at 10.566654 -17.566132 270)
			(size 0.4318 0.4318)
			(layers "F.Cu" "F.Mask" "F.Paste")
			(net "M_B_CPU0_SA_DQS_DN<8>")
		)
		(pad "AA60" smd circle
			(at 12.19454 -17.566132 270)
			(size 0.4318 0.4318)
			(layers "F.Cu" "F.Mask" "F.Paste")
			(net "GND")
		)
		(pad "AA62" smd circle
			(at 13.822426 -17.566132 270)
			(size 0.4318 0.4318)
			(layers "F.Cu" "F.Mask" "F.Paste")
			(net "GND")
		)
		(pad "AA64" smd circle
			(at 15.450058 -17.566132 270)
			(size 0.4318 0.4318)
			(layers "F.Cu" "F.Mask" "F.Paste")
			(net "M_C_CPU0_SA_DQS_DN<7>")
		)
		(pad "AA66" smd circle
			(at 17.07769 -17.566132 270)
			(size 0.4318 0.4318)
			(layers "F.Cu" "F.Mask" "F.Paste")
			(net "GND")
		)
		(pad "AA68" smd circle
			(at 18.705576 -17.566132 270)
			(size 0.4318 0.4318)
			(layers "F.Cu" "F.Mask" "F.Paste")
			(net "GND")
		)
		(pad "AA70" smd circle
			(at 20.333462 -17.566132 270)
			(size 0.4318 0.4318)
			(layers "F.Cu" "F.Mask" "F.Paste")
			(net "M_B_CPU0_SA_DQS_DN<6>")
		)
		(pad "AA72" smd circle
			(at 21.961094 -17.566132 270)
			(size 0.4318 0.4318)
			(layers "F.Cu" "F.Mask" "F.Paste")
			(net "GND")
		)
		(pad "AA74" smd circle
			(at 23.58898 -17.566132 270)
			(size 0.4318 0.4318)
			(layers "F.Cu" "F.Mask" "F.Paste")
			(net "GND")
		)
		(pad "AA76" smd circle
			(at 25.216612 -17.566132 270)
			(size 0.4318 0.4318)
			(layers "F.Cu" "F.Mask" "F.Paste")
			(net "M_C_CPU0_SA_DQS_DP<5>")
		)
		(pad "AA78" smd circle
			(at 26.844498 -17.566132 270)
			(size 0.4318 0.4318)
			(layers "F.Cu" "F.Mask" "F.Paste")
			(net "GND")
		)
		(pad "AA80" smd circle
			(at 28.472384 -17.566132 270)
			(size 0.4318 0.4318)
			(layers "F.Cu" "F.Mask" "F.Paste")
			(net "GND")
		)
		(pad "AA82" smd circle
			(at 30.100016 -17.566132 270)
			(size 0.4318 0.4318)
			(layers "F.Cu" "F.Mask" "F.Paste")
			(net "GND")
		)
		(pad "AA84" smd circle
			(at 31.727902 -17.566132 270)
			(size 0.4318 0.4318)
			(layers "F.Cu" "F.Mask" "F.Paste")
			(net "GND")
		)
		(pad "AA86" smd circle
			(at 33.355534 -17.566132 270)
			(size 0.4318 0.4318)
			(layers "F.Cu" "F.Mask" "F.Paste")
			(net "P5E_CPU0_PE4_TX_DN<5>")
		)
		(pad "AA88" smd circle
			(at 34.98342 -17.566132 270)
			(size 0.4318 0.4318)
			(layers "F.Cu" "F.Mask" "F.Paste")
			(net "GND")
		)
		(pad "AA90" smd circle
			(at 36.611306 -17.566132 270)
			(size 0.4318 0.4318)
			(layers "F.Cu" "F.Mask" "F.Paste")
			(net "P5E_CPU0_PE4_RX_DP<5>")
		)
		(pad "AB2" smd circle
			(at -36.611306 -17.206468 270)
			(size 0.4318 0.4318)
			(layers "F.Cu" "F.Mask" "F.Paste")
			(net "UPI_CPU0_CPU1_P0P1_DP<6>")
		)
		(pad "AB4" smd circle
			(at -34.98342 -17.206468 270)
			(size 0.4318 0.4318)
			(layers "F.Cu" "F.Mask" "F.Paste")
			(net "GND")
		)
		(pad "AB6" smd circle
			(at -33.355534 -17.206468 270)
			(size 0.4318 0.4318)
			(layers "F.Cu" "F.Mask" "F.Paste")
			(net "UPI_CPU1_CPU0_P1P0_DN<6>")
		)
		(pad "AB8" smd circle
			(at -31.727902 -17.206468 270)
			(size 0.4318 0.4318)
			(layers "F.Cu" "F.Mask" "F.Paste")
			(net "GND")
		)
		(pad "AB10" smd circle
			(at -30.100016 -17.206468 270)
			(size 0.4318 0.4318)
			(layers "F.Cu" "F.Mask" "F.Paste")
			(net "P5E_CPU0_PE0_RX_DN<6>")
		)
		(pad "AB12" smd circle
			(at -28.472384 -17.206468 270)
			(size 0.4318 0.4318)
			(layers "F.Cu" "F.Mask" "F.Paste")
			(net "GND")
		)
		(pad "AB14" smd circle
			(at -26.844498 -17.206468 270)
			(size 0.4318 0.4318)
			(layers "F.Cu" "F.Mask" "F.Paste")
			(net "P5E_CPU0_PE0_TX_DN<5>")
		)
		(pad "AB16" smd circle
			(at -25.216612 -17.206468 270)
			(size 0.4318 0.4318)
			(layers "F.Cu" "F.Mask" "F.Paste")
			(net "GND")
		)
		(pad "AB18" smd circle
			(at -23.58898 -17.206468 270)
			(size 0.4318 0.4318)
			(layers "F.Cu" "F.Mask" "F.Paste")
			(net "M_C_CPU0_SB_DQS_DN<3>")
		)
		(pad "AB20" smd circle
			(at -21.961094 -17.206468 270)
			(size 0.4318 0.4318)
			(layers "F.Cu" "F.Mask" "F.Paste")
			(net "GND")
		)
		(pad "AB22" smd circle
			(at -20.333462 -17.206468 270)
			(size 0.4318 0.4318)
			(layers "F.Cu" "F.Mask" "F.Paste")
			(net "GND")
		)
		(pad "AB24" smd circle
			(at -18.705576 -17.206468 270)
			(size 0.4318 0.4318)
			(layers "F.Cu" "F.Mask" "F.Paste")
			(net "M_D_CPU0_SB_DQS_DN<2>")
		)
		(pad "AB26" smd circle
			(at -17.07769 -17.206468 270)
			(size 0.4318 0.4318)
			(layers "F.Cu" "F.Mask" "F.Paste")
			(net "GND")
		)
		(pad "AB28" smd circle
			(at -15.450058 -17.206468 270)
			(size 0.4318 0.4318)
			(layers "F.Cu" "F.Mask" "F.Paste")
			(net "GND")
		)
		(pad "AB30" smd circle
			(at -13.822426 -17.206468 270)
			(size 0.4318 0.4318)
			(layers "F.Cu" "F.Mask" "F.Paste")
			(net "M_C_CPU0_SB_DQS_DN<1>")
		)
		(pad "AB32" smd circle
			(at -12.19454 -17.206468 270)
			(size 0.4318 0.4318)
			(layers "F.Cu" "F.Mask" "F.Paste")
			(net "GND")
		)
		(pad "AB34" smd circle
			(at -10.566654 -17.206468 270)
			(size 0.4318 0.4318)
			(layers "F.Cu" "F.Mask" "F.Paste")
			(net "GND")
		)
		(pad "AB36" smd circle
			(at -8.939022 -17.206468 270)
			(size 0.4318 0.4318)
			(layers "F.Cu" "F.Mask" "F.Paste")
			(net "M_C_CPU0_SB_DQS_DN<0>")
		)
		(pad "AB38" smd circle
			(at -7.311136 -17.206468 270)
			(size 0.4318 0.4318)
			(layers "F.Cu" "F.Mask" "F.Paste")
			(net "GND")
		)
		(pad "AB40" smd circle
			(at -5.68325 -17.206468 270)
			(size 0.4318 0.4318)
			(layers "F.Cu" "F.Mask" "F.Paste")
			(net "GND")
		)
		(pad "AB42" smd circle
			(at -4.055618 -17.206468 270)
			(size 0.4318 0.4318)
			(layers "F.Cu" "F.Mask" "F.Paste")
			(net "M_D_CPU0_SB_CA<6>")
		)
		(pad "AB44" smd circle
			(at -2.427732 -17.206468 270)
			(size 0.4318 0.4318)
			(layers "F.Cu" "F.Mask" "F.Paste")
			(net "GND")
		)
		(pad "AB47" smd circle
			(at 1.613916 -17.096486 270)
			(size 0.4318 0.4318)
			(layers "F.Cu" "F.Mask" "F.Paste")
			(net "GND")
		)
		(pad "AB49" smd circle
			(at 3.241802 -17.096486 270)
			(size 0.4318 0.4318)
			(layers "F.Cu" "F.Mask" "F.Paste")
			(net "M_C_CPU0_CLK_DN<0>")
		)
		(pad "AB51" smd circle
			(at 4.869434 -17.096486 270)
			(size 0.4318 0.4318)
			(layers "F.Cu" "F.Mask" "F.Paste")
			(net "GND")
		)
		(pad "AB53" smd circle
			(at 6.49732 -17.096486 270)
			(size 0.4318 0.4318)
			(layers "F.Cu" "F.Mask" "F.Paste")
			(net "GND")
		)
		(pad "AB55" smd circle
			(at 8.124952 -17.096486 270)
			(size 0.4318 0.4318)
			(layers "F.Cu" "F.Mask" "F.Paste")
			(net "M_C_CPU0_SA_DQS_DP<4>")
		)
		(pad "AB57" smd circle
			(at 9.752838 -17.096486 270)
			(size 0.4318 0.4318)
			(layers "F.Cu" "F.Mask" "F.Paste")
			(net "GND")
		)
		(pad "AB59" smd circle
			(at 11.380724 -17.096486 270)
			(size 0.4318 0.4318)
			(layers "F.Cu" "F.Mask" "F.Paste")
			(net "GND")
		)
		(pad "AB61" smd circle
			(at 13.008356 -17.096486 270)
			(size 0.4318 0.4318)
			(layers "F.Cu" "F.Mask" "F.Paste")
			(net "M_C_CPU0_SA_DQS_DN<3>")
		)
		(pad "AB63" smd circle
			(at 14.635988 -17.096486 270)
			(size 0.4318 0.4318)
			(layers "F.Cu" "F.Mask" "F.Paste")
			(net "GND")
		)
		(pad "AB65" smd circle
			(at 16.263874 -17.096486 270)
			(size 0.4318 0.4318)
			(layers "F.Cu" "F.Mask" "F.Paste")
			(net "GND")
		)
		(pad "AB67" smd circle
			(at 17.89176 -17.096486 270)
			(size 0.4318 0.4318)
			(layers "F.Cu" "F.Mask" "F.Paste")
			(net "M_C_CPU0_SA_DQS_DN<1>")
		)
		(pad "AB69" smd circle
			(at 19.519392 -17.096486 270)
			(size 0.4318 0.4318)
			(layers "F.Cu" "F.Mask" "F.Paste")
			(net "GND")
		)
	)
)
